(kicad_pcb
	(version 20260206)
	(generator "pcbnew")
	(generator_version "10.0")
	(general
		(thickness 1.6)
		(legacy_teardrops no)
	)
	(paper "A4")
	(title_block
		(title "12092022_DA0F0TMDCD0_F0T_Management_Board_D_brd_V3_OCP.brd")
		(comment 1 "Grand Teton / footprints 1004-1009 of 1440")
	)
	(layers
		(0 "F.Cu" signal "TOP")
		(4 "In1.Cu" signal "GND")
		(6 "In2.Cu" signal "IN1")
		(8 "In3.Cu" signal "GND1")
		(10 "In4.Cu" signal "IN2")
		(12 "In5.Cu" signal "VCC")
		(14 "In6.Cu" signal "VCC1")
		(16 "In7.Cu" signal "IN3")
		(18 "In8.Cu" signal "GND2")
		(20 "In9.Cu" signal "IN4")
		(22 "In10.Cu" signal "GND3")
		(2 "B.Cu" signal "BOTTOM")
		(9 "F.Adhes" user "F.Adhesive")
		(11 "B.Adhes" user "B.Adhesive")
		(13 "F.Paste" user "Package Geometry/Pastemask Top")
		(15 "B.Paste" user "Package Geometry/Pastemask Bottom")
		(5 "F.SilkS" user "Ref Des/Silkscreen Top")
		(7 "B.SilkS" user "Ref Des/Silkscreen Bottom")
		(1 "F.Mask" user "Board Geometry/Soldermask Top")
		(3 "B.Mask" user "Board Geometry/Soldermask Bottom")
		(17 "Dwgs.User" user "User.Drawings")
		(19 "Cmts.User" user "User.Comments")
		(21 "Eco1.User" user "User.Eco1")
		(23 "Eco2.User" user "User.Eco2")
		(25 "Edge.Cuts" user "Board Geometry/Outline")
		(27 "Margin" user)
		(31 "F.CrtYd" user "Package Geometry/Place Bound Top")
		(29 "B.CrtYd" user "Package Geometry/Place Bound Bottom")
		(35 "F.Fab" user "Ref Des/Assembly Top")
		(33 "B.Fab" user "Ref Des/Assembly Bottom")
	)
	(footprint ""
		(layer "B.Cu")
		(at 29.1846 -27.7622)
		(property "Reference" "C212"
			(at 0 0 0)
			(layer "B.SilkS")
			(hide yes)
			(effects
				(font
					(size 1.27 1.27)
				)
				(justify mirror)
			)
		)
		(property "Value" ""
			(at 0 0 0)
			(layer "B.Fab")
			(effects
				(font
					(size 1.27 1.27)
				)
				(justify mirror)
			)
		)
		(duplicate_pad_numbers_are_jumpers no)
		(fp_line
			(start -0.7874 -0.4064)
			(end -0.7874 0.4064)
			(stroke
				(width 0.1524)
				(type default)
			)
			(layer "B.SilkS")
		)
		(fp_line
			(start -0.7874 0.4064)
			(end 0.7874 0.4064)
			(stroke
				(width 0.1524)
				(type default)
			)
			(layer "B.SilkS")
		)
		(fp_line
			(start 0.7874 -0.4064)
			(end -0.7874 -0.4064)
			(stroke
				(width 0.1524)
				(type default)
			)
			(layer "B.SilkS")
		)
		(fp_line
			(start 0.7874 0.4064)
			(end 0.7874 -0.4064)
			(stroke
				(width 0.1524)
				(type default)
			)
			(layer "B.SilkS")
		)
		(fp_line
			(start -0.67945 -0.3048)
			(end -0.67945 0.3048)
			(stroke
				(width 0.1)
				(type default)
			)
			(layer "B.Fab")
		)
		(fp_line
			(start -0.67945 0.3048)
			(end -0.120396 0.3048)
			(stroke
				(width 0.1)
				(type default)
			)
			(layer "B.Fab")
		)
		(fp_line
			(start -0.12065 -0.3048)
			(end -0.67945 -0.3048)
			(stroke
				(width 0.1)
				(type default)
			)
			(layer "B.Fab")
		)
		(fp_line
			(start -0.12065 -0.2794)
			(end -0.12065 -0.3048)
			(stroke
				(width 0.1)
				(type default)
			)
			(layer "B.Fab")
		)
		(fp_line
			(start -0.120396 0.2794)
			(end 0.12065 0.2794)
			(stroke
				(width 0.1)
				(type default)
			)
			(layer "B.Fab")
		)
		(fp_line
			(start -0.120396 0.3048)
			(end -0.120396 0.2794)
			(stroke
				(width 0.1)
				(type default)
			)
			(layer "B.Fab")
		)
		(fp_line
			(start 0.12065 -0.305054)
			(end 0.12065 -0.2794)
			(stroke
				(width 0.1)
				(type default)
			)
			(layer "B.Fab")
		)
		(fp_line
			(start 0.12065 -0.2794)
			(end -0.12065 -0.2794)
			(stroke
				(width 0.1)
				(type default)
			)
			(layer "B.Fab")
		)
		(fp_line
			(start 0.12065 0.2794)
			(end 0.12065 0.3048)
			(stroke
				(width 0.1)
				(type default)
			)
			(layer "B.Fab")
		)
		(fp_line
			(start 0.12065 0.3048)
			(end 0.67945 0.3048)
			(stroke
				(width 0.1)
				(type default)
			)
			(layer "B.Fab")
		)
		(fp_line
			(start 0.67945 -0.305054)
			(end 0.12065 -0.305054)
			(stroke
				(width 0.1)
				(type default)
			)
			(layer "B.Fab")
		)
		(fp_line
			(start 0.67945 0.3048)
			(end 0.67945 -0.305054)
			(stroke
				(width 0.1)
				(type default)
			)
			(layer "B.Fab")
		)
		(pad "1" smd circle
			(at 0.40005 0 180)
			(size 0 0)
			(layers "B.Cu" "B.Mask" "B.Paste")
			(net "V_VGAVS_BUF")
		)
		(pad "2" smd circle
			(at -0.40005 0 180)
			(size 0 0)
			(layers "B.Cu" "B.Mask" "B.Paste")
			(net "GND")
		)
	)
	(footprint ""
		(layer "B.Cu")
		(at 61.996828 -27.875992 90)
		(property "Reference" "R851"
			(at 0 0 90)
			(layer "B.SilkS")
			(hide yes)
			(effects
				(font
					(size 1.27 1.27)
				)
				(justify mirror)
			)
		)
		(property "Value" ""
			(at 0 0 90)
			(layer "B.Fab")
			(effects
				(font
					(size 1.27 1.27)
				)
				(justify mirror)
			)
		)
		(duplicate_pad_numbers_are_jumpers no)
		(fp_line
			(start 0.7874 -0.4064)
			(end -0.7874 -0.4064)
			(stroke
				(width 0.1524)
				(type default)
			)
			(layer "B.SilkS")
		)
		(fp_line
			(start -0.7874 -0.4064)
			(end -0.7874 0.4064)
			(stroke
				(width 0.1524)
				(type default)
			)
			(layer "B.SilkS")
		)
		(fp_line
			(start 0.7874 0.4064)
			(end 0.7874 -0.4064)
			(stroke
				(width 0.1524)
				(type default)
			)
			(layer "B.SilkS")
		)
		(fp_line
			(start -0.7874 0.4064)
			(end 0.7874 0.4064)
			(stroke
				(width 0.1524)
				(type default)
			)
			(layer "B.SilkS")
		)
		(fp_line
			(start 0.67945 -0.305054)
			(end 0.12065 -0.305054)
			(stroke
				(width 0.1)
				(type default)
			)
			(layer "B.Fab")
		)
		(fp_line
			(start 0.12065 -0.305054)
			(end 0.12065 -0.2794)
			(stroke
				(width 0.1)
				(type default)
			)
			(layer "B.Fab")
		)
		(fp_line
			(start -0.12065 -0.3048)
			(end -0.67945 -0.3048)
			(stroke
				(width 0.1)
				(type default)
			)
			(layer "B.Fab")
		)
		(fp_line
			(start -0.67945 -0.3048)
			(end -0.67945 0.3048)
			(stroke
				(width 0.1)
				(type default)
			)
			(layer "B.Fab")
		)
		(fp_line
			(start 0.12065 -0.2794)
			(end -0.12065 -0.2794)
			(stroke
				(width 0.1)
				(type default)
			)
			(layer "B.Fab")
		)
		(fp_line
			(start -0.12065 -0.2794)
			(end -0.12065 -0.3048)
			(stroke
				(width 0.1)
				(type default)
			)
			(layer "B.Fab")
		)
		(fp_line
			(start 0.12065 0.2794)
			(end 0.12065 0.3048)
			(stroke
				(width 0.1)
				(type default)
			)
			(layer "B.Fab")
		)
		(fp_line
			(start -0.120396 0.2794)
			(end 0.12065 0.2794)
			(stroke
				(width 0.1)
				(type default)
			)
			(layer "B.Fab")
		)
		(fp_line
			(start 0.67945 0.3048)
			(end 0.67945 -0.305054)
			(stroke
				(width 0.1)
				(type default)
			)
			(layer "B.Fab")
		)
		(fp_line
			(start 0.12065 0.3048)
			(end 0.67945 0.3048)
			(stroke
				(width 0.1)
				(type default)
			)
			(layer "B.Fab")
		)
		(fp_line
			(start -0.120396 0.3048)
			(end -0.120396 0.2794)
			(stroke
				(width 0.1)
				(type default)
			)
			(layer "B.Fab")
		)
		(fp_line
			(start -0.67945 0.3048)
			(end -0.120396 0.3048)
			(stroke
				(width 0.1)
				(type default)
			)
			(layer "B.Fab")
		)
		(pad "1" smd circle
			(at 0.40005 0 270)
			(size 0 0)
			(layers "B.Cu" "B.Mask" "B.Paste")
			(net "P3V3_AUX")
		)
		(pad "2" smd circle
			(at -0.40005 0 270)
			(size 0 0)
			(layers "B.Cu" "B.Mask" "B.Paste")
			(net "SMB_BMC_ALERT15_N")
		)
	)
	(footprint ""
		(layer "B.Cu")
		(at 59.3852 -77.9526)
		(property "Reference" "R547"
			(at 0 0 0)
			(layer "B.SilkS")
			(hide yes)
			(effects
				(font
					(size 1.27 1.27)
				)
				(justify mirror)
			)
		)
		(property "Value" ""
			(at 0 0 0)
			(layer "B.Fab")
			(effects
				(font
					(size 1.27 1.27)
				)
				(justify mirror)
			)
		)
		(duplicate_pad_numbers_are_jumpers no)
		(fp_line
			(start -0.7874 -0.4064)
			(end -0.7874 0.4064)
			(stroke
				(width 0.1524)
				(type default)
			)
			(layer "B.SilkS")
		)
		(fp_line
			(start -0.7874 0.4064)
			(end 0.7874 0.4064)
			(stroke
				(width 0.1524)
				(type default)
			)
			(layer "B.SilkS")
		)
		(fp_line
			(start 0.7874 -0.4064)
			(end -0.7874 -0.4064)
			(stroke
				(width 0.1524)
				(type default)
			)
			(layer "B.SilkS")
		)
		(fp_line
			(start 0.7874 0.4064)
			(end 0.7874 -0.4064)
			(stroke
				(width 0.1524)
				(type default)
			)
			(layer "B.SilkS")
		)
		(fp_line
			(start -0.67945 -0.3048)
			(end -0.67945 0.3048)
			(stroke
				(width 0.1)
				(type default)
			)
			(layer "B.Fab")
		)
		(fp_line
			(start -0.67945 0.3048)
			(end -0.120396 0.3048)
			(stroke
				(width 0.1)
				(type default)
			)
			(layer "B.Fab")
		)
		(fp_line
			(start -0.12065 -0.3048)
			(end -0.67945 -0.3048)
			(stroke
				(width 0.1)
				(type default)
			)
			(layer "B.Fab")
		)
		(fp_line
			(start -0.12065 -0.2794)
			(end -0.12065 -0.3048)
			(stroke
				(width 0.1)
				(type default)
			)
			(layer "B.Fab")
		)
		(fp_line
			(start -0.120396 0.2794)
			(end 0.12065 0.2794)
			(stroke
				(width 0.1)
				(type default)
			)
			(layer "B.Fab")
		)
		(fp_line
			(start -0.120396 0.3048)
			(end -0.120396 0.2794)
			(stroke
				(width 0.1)
				(type default)
			)
			(layer "B.Fab")
		)
		(fp_line
			(start 0.12065 -0.305054)
			(end 0.12065 -0.2794)
			(stroke
				(width 0.1)
				(type default)
			)
			(layer "B.Fab")
		)
		(fp_line
			(start 0.12065 -0.2794)
			(end -0.12065 -0.2794)
			(stroke
				(width 0.1)
				(type default)
			)
			(layer "B.Fab")
		)
		(fp_line
			(start 0.12065 0.2794)
			(end 0.12065 0.3048)
			(stroke
				(width 0.1)
				(type default)
			)
			(layer "B.Fab")
		)
		(fp_line
			(start 0.12065 0.3048)
			(end 0.67945 0.3048)
			(stroke
				(width 0.1)
				(type default)
			)
			(layer "B.Fab")
		)
		(fp_line
			(start 0.67945 -0.305054)
			(end 0.12065 -0.305054)
			(stroke
				(width 0.1)
				(type default)
			)
			(layer "B.Fab")
		)
		(fp_line
			(start 0.67945 0.3048)
			(end 0.67945 -0.305054)
			(stroke
				(width 0.1)
				(type default)
			)
			(layer "B.Fab")
		)
		(pad "1" smd circle
			(at 0.40005 0 180)
			(size 0 0)
			(layers "B.Cu" "B.Mask" "B.Paste")
			(net "SPI_BMC_CS1_FLASH_R_N")
		)
		(pad "2" smd circle
			(at -0.40005 0 180)
			(size 0 0)
			(layers "B.Cu" "B.Mask" "B.Paste")
			(net "SPI_BMC_BOOT_CS1_R_N")
		)
	)
	(footprint ""
		(layer "B.Cu")
		(at 26.416 -92.075 90)
		(property "Reference" "R301"
			(at 0 0 90)
			(layer "B.SilkS")
			(hide yes)
			(effects
				(font
					(size 1.27 1.27)
				)
				(justify mirror)
			)
		)
		(property "Value" ""
			(at 0 0 90)
			(layer "B.Fab")
			(effects
				(font
					(size 1.27 1.27)
				)
				(justify mirror)
			)
		)
		(duplicate_pad_numbers_are_jumpers no)
		(fp_line
			(start 0.7874 -0.4064)
			(end -0.7874 -0.4064)
			(stroke
				(width 0.1524)
				(type default)
			)
			(layer "B.SilkS")
		)
		(fp_line
			(start -0.7874 -0.4064)
			(end -0.7874 0.4064)
			(stroke
				(width 0.1524)
				(type default)
			)
			(layer "B.SilkS")
		)
		(fp_line
			(start 0.7874 0.4064)
			(end 0.7874 -0.4064)
			(stroke
				(width 0.1524)
				(type default)
			)
			(layer "B.SilkS")
		)
		(fp_line
			(start -0.7874 0.4064)
			(end 0.7874 0.4064)
			(stroke
				(width 0.1524)
				(type default)
			)
			(layer "B.SilkS")
		)
		(fp_line
			(start 0.67945 -0.305054)
			(end 0.12065 -0.305054)
			(stroke
				(width 0.1)
				(type default)
			)
			(layer "B.Fab")
		)
		(fp_line
			(start 0.12065 -0.305054)
			(end 0.12065 -0.2794)
			(stroke
				(width 0.1)
				(type default)
			)
			(layer "B.Fab")
		)
		(fp_line
			(start -0.12065 -0.3048)
			(end -0.67945 -0.3048)
			(stroke
				(width 0.1)
				(type default)
			)
			(layer "B.Fab")
		)
		(fp_line
			(start -0.67945 -0.3048)
			(end -0.67945 0.3048)
			(stroke
				(width 0.1)
				(type default)
			)
			(layer "B.Fab")
		)
		(fp_line
			(start 0.12065 -0.2794)
			(end -0.12065 -0.2794)
			(stroke
				(width 0.1)
				(type default)
			)
			(layer "B.Fab")
		)
		(fp_line
			(start -0.12065 -0.2794)
			(end -0.12065 -0.3048)
			(stroke
				(width 0.1)
				(type default)
			)
			(layer "B.Fab")
		)
		(fp_line
			(start 0.12065 0.2794)
			(end 0.12065 0.3048)
			(stroke
				(width 0.1)
				(type default)
			)
			(layer "B.Fab")
		)
		(fp_line
			(start -0.120396 0.2794)
			(end 0.12065 0.2794)
			(stroke
				(width 0.1)
				(type default)
			)
			(layer "B.Fab")
		)
		(fp_line
			(start 0.67945 0.3048)
			(end 0.67945 -0.305054)
			(stroke
				(width 0.1)
				(type default)
			)
			(layer "B.Fab")
		)
		(fp_line
			(start 0.12065 0.3048)
			(end 0.67945 0.3048)
			(stroke
				(width 0.1)
				(type default)
			)
			(layer "B.Fab")
		)
		(fp_line
			(start -0.120396 0.3048)
			(end -0.120396 0.2794)
			(stroke
				(width 0.1)
				(type default)
			)
			(layer "B.Fab")
		)
		(fp_line
			(start -0.67945 0.3048)
			(end -0.120396 0.3048)
			(stroke
				(width 0.1)
				(type default)
			)
			(layer "B.Fab")
		)
		(pad "1" smd circle
			(at 0.40005 0 270)
			(size 0 0)
			(layers "B.Cu" "B.Mask" "B.Paste")
			(net "P3V3_AUX")
		)
		(pad "2" smd circle
			(at -0.40005 0 270)
			(size 0 0)
			(layers "B.Cu" "B.Mask" "B.Paste")
			(net "VCCIO5")
		)
	)
	(footprint ""
		(layer "B.Cu")
		(at 43.367198 -34.637726 90)
		(property "Reference" "R394"
			(at 0 0 90)
			(layer "B.SilkS")
			(hide yes)
			(effects
				(font
					(size 1.27 1.27)
				)
				(justify mirror)
			)
		)
		(property "Value" ""
			(at 0 0 90)
			(layer "B.Fab")
			(effects
				(font
					(size 1.27 1.27)
				)
				(justify mirror)
			)
		)
		(duplicate_pad_numbers_are_jumpers no)
		(fp_line
			(start 0.7874 -0.4064)
			(end -0.7874 -0.4064)
			(stroke
				(width 0.1524)
				(type default)
			)
			(layer "B.SilkS")
		)
		(fp_line
			(start -0.7874 -0.4064)
			(end -0.7874 0.4064)
			(stroke
				(width 0.1524)
				(type default)
			)
			(layer "B.SilkS")
		)
		(fp_line
			(start 0.7874 0.4064)
			(end 0.7874 -0.4064)
			(stroke
				(width 0.1524)
				(type default)
			)
			(layer "B.SilkS")
		)
		(fp_line
			(start -0.7874 0.4064)
			(end 0.7874 0.4064)
			(stroke
				(width 0.1524)
				(type default)
			)
			(layer "B.SilkS")
		)
		(fp_line
			(start 0.67945 -0.305054)
			(end 0.12065 -0.305054)
			(stroke
				(width 0.1)
				(type default)
			)
			(layer "B.Fab")
		)
		(fp_line
			(start 0.12065 -0.305054)
			(end 0.12065 -0.2794)
			(stroke
				(width 0.1)
				(type default)
			)
			(layer "B.Fab")
		)
		(fp_line
			(start -0.12065 -0.3048)
			(end -0.67945 -0.3048)
			(stroke
				(width 0.1)
				(type default)
			)
			(layer "B.Fab")
		)
		(fp_line
			(start -0.67945 -0.3048)
			(end -0.67945 0.3048)
			(stroke
				(width 0.1)
				(type default)
			)
			(layer "B.Fab")
		)
		(fp_line
			(start 0.12065 -0.2794)
			(end -0.12065 -0.2794)
			(stroke
				(width 0.1)
				(type default)
			)
			(layer "B.Fab")
		)
		(fp_line
			(start -0.12065 -0.2794)
			(end -0.12065 -0.3048)
			(stroke
				(width 0.1)
				(type default)
			)
			(layer "B.Fab")
		)
		(fp_line
			(start 0.12065 0.2794)
			(end 0.12065 0.3048)
			(stroke
				(width 0.1)
				(type default)
			)
			(layer "B.Fab")
		)
		(fp_line
			(start -0.120396 0.2794)
			(end 0.12065 0.2794)
			(stroke
				(width 0.1)
				(type default)
			)
			(layer "B.Fab")
		)
		(fp_line
			(start 0.67945 0.3048)
			(end 0.67945 -0.305054)
			(stroke
				(width 0.1)
				(type default)
			)
			(layer "B.Fab")
		)
		(fp_line
			(start 0.12065 0.3048)
			(end 0.67945 0.3048)
			(stroke
				(width 0.1)
				(type default)
			)
			(layer "B.Fab")
		)
		(fp_line
			(start -0.120396 0.3048)
			(end -0.120396 0.2794)
			(stroke
				(width 0.1)
				(type default)
			)
			(layer "B.Fab")
		)
		(fp_line
			(start -0.67945 0.3048)
			(end -0.120396 0.3048)
			(stroke
				(width 0.1)
				(type default)
			)
			(layer "B.Fab")
		)
		(pad "1" smd circle
			(at 0.40005 0 270)
			(size 0 0)
			(layers "B.Cu" "B.Mask" "B.Paste")
			(net "SMB_BMC_MM2_R_SDA")
		)
		(pad "2" smd circle
			(at -0.40005 0 270)
			(size 0 0)
			(layers "B.Cu" "B.Mask" "B.Paste")
			(net "SMB_BMC_MM2_SDA")
		)
	)
	(footprint ""
		(layer "B.Cu")
		(at 76.691744 -37.559488 90)
		(property "Reference" "R362"
			(at 0 0 90)
			(layer "B.SilkS")
			(hide yes)
			(effects
				(font
					(size 1.27 1.27)
				)
				(justify mirror)
			)
		)
		(property "Value" ""
			(at 0 0 90)
			(layer "B.Fab")
			(effects
				(font
					(size 1.27 1.27)
				)
				(justify mirror)
			)
		)
		(duplicate_pad_numbers_are_jumpers no)
		(fp_line
			(start 0.7874 -0.4064)
			(end -0.7874 -0.4064)
			(stroke
				(width 0.1524)
				(type default)
			)
			(layer "B.SilkS")
		)
		(fp_line
			(start -0.7874 -0.4064)
			(end -0.7874 0.4064)
			(stroke
				(width 0.1524)
				(type default)
			)
			(layer "B.SilkS")
		)
		(fp_line
			(start 0.7874 0.4064)
			(end 0.7874 -0.4064)
			(stroke
				(width 0.1524)
				(type default)
			)
			(layer "B.SilkS")
		)
		(fp_line
			(start -0.7874 0.4064)
			(end 0.7874 0.4064)
			(stroke
				(width 0.1524)
				(type default)
			)
			(layer "B.SilkS")
		)
		(fp_line
			(start 0.67945 -0.305054)
			(end 0.12065 -0.305054)
			(stroke
				(width 0.1)
				(type default)
			)
			(layer "B.Fab")
		)
		(fp_line
			(start 0.12065 -0.305054)
			(end 0.12065 -0.2794)
			(stroke
				(width 0.1)
				(type default)
			)
			(layer "B.Fab")
		)
		(fp_line
			(start -0.12065 -0.3048)
			(end -0.67945 -0.3048)
			(stroke
				(width 0.1)
				(type default)
			)
			(layer "B.Fab")
		)
		(fp_line
			(start -0.67945 -0.3048)
			(end -0.67945 0.3048)
			(stroke
				(width 0.1)
				(type default)
			)
			(layer "B.Fab")
		)
		(fp_line
			(start 0.12065 -0.2794)
			(end -0.12065 -0.2794)
			(stroke
				(width 0.1)
				(type default)
			)
			(layer "B.Fab")
		)
		(fp_line
			(start -0.12065 -0.2794)
			(end -0.12065 -0.3048)
			(stroke
				(width 0.1)
				(type default)
			)
			(layer "B.Fab")
		)
		(fp_line
			(start 0.12065 0.2794)
			(end 0.12065 0.3048)
			(stroke
				(width 0.1)
				(type default)
			)
			(layer "B.Fab")
		)
		(fp_line
			(start -0.120396 0.2794)
			(end 0.12065 0.2794)
			(stroke
				(width 0.1)
				(type default)
			)
			(layer "B.Fab")
		)
		(fp_line
			(start 0.67945 0.3048)
			(end 0.67945 -0.305054)
			(stroke
				(width 0.1)
				(type default)
			)
			(layer "B.Fab")
		)
		(fp_line
			(start 0.12065 0.3048)
			(end 0.67945 0.3048)
			(stroke
				(width 0.1)
				(type default)
			)
			(layer "B.Fab")
		)
		(fp_line
			(start -0.120396 0.3048)
			(end -0.120396 0.2794)
			(stroke
				(width 0.1)
				(type default)
			)
			(layer "B.Fab")
		)
		(fp_line
			(start -0.67945 0.3048)
			(end -0.120396 0.3048)
			(stroke
				(width 0.1)
				(type default)
			)
			(layer "B.Fab")
		)
		(pad "1" smd circle
			(at 0.40005 0 270)
			(size 0 0)
			(layers "B.Cu" "B.Mask" "B.Paste")
			(net "M_BMC_DDR4_MA<11>")
		)
		(pad "2" smd circle
			(at -0.40005 0 270)
			(size 0 0)
			(layers "B.Cu" "B.Mask" "B.Paste")
			(net "P1V2_AUX")
		)
	)
)
